# T6G (Grand Teton) — schematic netlist excerpt (pin names and nets, part order shuffled) for the footprints in the layout excerpt that follows; sources: Cadence DE-HDL packaged netlist, KiCad conversion of 04192023_DAF0TMB3IC0_F0TG_MB_C_brd_V02_OCP.brd

R1430  Q_RES  4.7K 5% CHIP  pkg 0201LF  page 353 : A = JTAG_TCK_RT_CPU1_P3 ; B = GND
R3751  Q_RES  0 5% CHIP  pkg 0402LF  page 236 : A = INA230_2_A0 ; B = SMB_INA230_2_3V3AUX_SDA_R1
C607  Q_CAP  1UF 4V 20% X6S  pkg 0201  page 290 : A = P0V9_CPU0_RT1_2A ; B = GND
C522  Q_CAP  0.1UF 10V 10% X7S  pkg C0201  page 279 : A = P0V9_CPU0_RT_2D ; B = GND

(kicad_pcb
	(version 20260206)
	(generator "pcbnew")
	(generator_version "10.0")
	(general
		(thickness 1.6)
		(legacy_teardrops no)
	)
	(paper "A4")
	(title_block
		(title "04192023_DAF0TMB3IC0_F0TG_MB_C_brd_V02_OCP.brd")
		(comment 1 "Grand Teton / footprints 5264-5267 of 8354")
	)
	(layers
		(0 "F.Cu" signal "TOP")
		(4 "In1.Cu" signal "GND")
		(6 "In2.Cu" signal "IN1")
		(8 "In3.Cu" signal "GND1")
		(10 "In4.Cu" signal "IN2")
		(12 "In5.Cu" signal "GND2")
		(14 "In6.Cu" signal "IN3")
		(16 "In7.Cu" signal "GND3")
		(18 "In8.Cu" signal "VCC")
		(20 "In9.Cu" signal "VCC1")
		(22 "In10.Cu" signal "GND4")
		(24 "In11.Cu" signal "IN4")
		(26 "In12.Cu" signal "GND5")
		(28 "In13.Cu" signal "IN5")
		(30 "In14.Cu" signal "GND6")
		(32 "In15.Cu" signal "IN6")
		(34 "In16.Cu" signal "GND7")
		(2 "B.Cu" signal "BOTTOM")
		(9 "F.Adhes" user "F.Adhesive")
		(11 "B.Adhes" user "B.Adhesive")
		(13 "F.Paste" user "Package Geometry/Pastemask Top")
		(15 "B.Paste" user "Package Geometry/Pastemask Bottom")
		(5 "F.SilkS" user "Ref Des/Silkscreen Top")
		(7 "B.SilkS" user "Ref Des/Silkscreen Bottom")
		(1 "F.Mask" user "Board Geometry/Soldermask Top")
		(3 "B.Mask" user "Board Geometry/Soldermask Bottom")
		(17 "Dwgs.User" user "User.Drawings")
		(19 "Cmts.User" user "User.Comments")
		(21 "Eco1.User" user "User.Eco1")
		(23 "Eco2.User" user "User.Eco2")
		(25 "Edge.Cuts" user "Board Geometry/Outline")
		(27 "Margin" user)
		(31 "F.CrtYd" user "Package Geometry/Place Bound Top")
		(29 "B.CrtYd" user "Package Geometry/Place Bound Bottom")
		(35 "F.Fab" user "Ref Des/Assembly Top")
		(33 "B.Fab" user "Ref Des/Assembly Bottom")
	)
	(footprint ""
		(layer "B.Cu")
		(at 339.506052 -395.148562 90)
		(property "Reference" "C607"
			(at 0 0 90)
			(layer "B.SilkS")
			(hide yes)
			(effects
				(font
					(size 1.27 1.27)
				)
				(justify mirror)
			)
		)
		(property "Value" ""
			(at 0 0 90)
			(layer "B.Fab")
			(effects
				(font
					(size 1.27 1.27)
				)
				(justify mirror)
			)
		)
		(duplicate_pad_numbers_are_jumpers no)
		(fp_line
			(start 0.299974 -0.150114)
			(end -0.299974 -0.150114)
			(stroke
				(width 0.1)
				(type default)
			)
			(layer "B.Fab")
		)
		(fp_line
			(start -0.299974 -0.150114)
			(end -0.299974 0.150114)
			(stroke
				(width 0.1)
				(type default)
			)
			(layer "B.Fab")
		)
		(fp_line
			(start 0.299974 0.150114)
			(end 0.299974 -0.150114)
			(stroke
				(width 0.1)
				(type default)
			)
			(layer "B.Fab")
		)
		(fp_line
			(start -0.299974 0.150114)
			(end 0.299974 0.150114)
			(stroke
				(width 0.1)
				(type default)
			)
			(layer "B.Fab")
		)
		(pad "1" smd rect
			(at 0.2667 0 270)
			(size 0.3048 0.381)
			(layers "B.Cu" "B.Mask" "B.Paste")
			(net "P0V9_CPU0_RT1_2A")
		)
		(pad "2" smd rect
			(at -0.2667 0 270)
			(size 0.3048 0.381)
			(layers "B.Cu" "B.Mask" "B.Paste")
			(net "GND")
		)
	)
	(footprint ""
		(layer "B.Cu")
		(at 164.465 -426.4152 -90)
		(property "Reference" "R1430"
			(at 0 0 90)
			(layer "B.SilkS")
			(hide yes)
			(effects
				(font
					(size 1.27 1.27)
				)
				(justify mirror)
			)
		)
		(property "Value" ""
			(at 0 0 90)
			(layer "B.Fab")
			(effects
				(font
					(size 1.27 1.27)
				)
				(justify mirror)
			)
		)
		(duplicate_pad_numbers_are_jumpers no)
		(fp_line
			(start -0.32512 0.175006)
			(end 0.32512 0.175006)
			(stroke
				(width 0.1)
				(type default)
			)
			(layer "B.Fab")
		)
		(fp_line
			(start 0.32512 0.175006)
			(end 0.32512 -0.175006)
			(stroke
				(width 0.1)
				(type default)
			)
			(layer "B.Fab")
		)
		(fp_line
			(start -0.32512 -0.175006)
			(end -0.32512 0.175006)
			(stroke
				(width 0.1)
				(type default)
			)
			(layer "B.Fab")
		)
		(fp_line
			(start 0.32512 -0.175006)
			(end -0.32512 -0.175006)
			(stroke
				(width 0.1)
				(type default)
			)
			(layer "B.Fab")
		)
		(pad "1" smd rect
			(at 0.2667 0 90)
			(size 0.3048 0.381)
			(layers "B.Cu" "B.Mask" "B.Paste")
			(net "JTAG_TCK_RT_CPU1_P3")
		)
		(pad "2" smd rect
			(at -0.2667 0 270)
			(size 0.3048 0.381)
			(layers "B.Cu" "B.Mask" "B.Paste")
			(net "GND")
		)
	)
	(footprint ""
		(layer "B.Cu")
		(at 309.518304 -396.393162 -90)
		(property "Reference" "C522"
			(at 0 0 90)
			(layer "B.SilkS")
			(hide yes)
			(effects
				(font
					(size 1.27 1.27)
				)
				(justify mirror)
			)
		)
		(property "Value" ""
			(at 0 0 90)
			(layer "B.Fab")
			(effects
				(font
					(size 1.27 1.27)
				)
				(justify mirror)
			)
		)
		(duplicate_pad_numbers_are_jumpers no)
		(fp_line
			(start -0.299974 0.150114)
			(end 0.299974 0.150114)
			(stroke
				(width 0.1)
				(type default)
			)
			(layer "B.Fab")
		)
		(fp_line
			(start 0.299974 0.150114)
			(end 0.299974 -0.150114)
			(stroke
				(width 0.1)
				(type default)
			)
			(layer "B.Fab")
		)
		(fp_line
			(start -0.299974 -0.150114)
			(end -0.299974 0.150114)
			(stroke
				(width 0.1)
				(type default)
			)
			(layer "B.Fab")
		)
		(fp_line
			(start 0.299974 -0.150114)
			(end -0.299974 -0.150114)
			(stroke
				(width 0.1)
				(type default)
			)
			(layer "B.Fab")
		)
		(pad "1" smd rect
			(at 0.2667 0 90)
			(size 0.3048 0.381)
			(layers "B.Cu" "B.Mask" "B.Paste")
			(net "P0V9_CPU0_RT_2D")
		)
		(pad "2" smd rect
			(at -0.2667 0 90)
			(size 0.3048 0.381)
			(layers "B.Cu" "B.Mask" "B.Paste")
			(net "GND")
		)
	)
	(footprint ""
		(layer "B.Cu")
		(at 213.79688 -54.447948 90)
		(property "Reference" "R3751"
			(at 0 0 90)
			(layer "B.SilkS")
			(hide yes)
			(effects
				(font
					(size 1.27 1.27)
				)
				(justify mirror)
			)
		)
		(property "Value" ""
			(at 0 0 90)
			(layer "B.Fab")
			(effects
				(font
					(size 1.27 1.27)
				)
				(justify mirror)
			)
		)
		(duplicate_pad_numbers_are_jumpers no)
		(fp_line
			(start 0.7874 -0.4064)
			(end -0.7874 -0.4064)
			(stroke
				(width 0.1524)
				(type default)
			)
			(layer "B.SilkS")
		)
		(fp_line
			(start -0.7874 -0.4064)
			(end -0.7874 0.4064)
			(stroke
				(width 0.1524)
				(type default)
			)
			(layer "B.SilkS")
		)
		(fp_line
			(start 0.7874 0.4064)
			(end 0.7874 -0.4064)
			(stroke
				(width 0.1524)
				(type default)
			)
			(layer "B.SilkS")
		)
		(fp_line
			(start -0.7874 0.4064)
			(end 0.7874 0.4064)
			(stroke
				(width 0.1524)
				(type default)
			)
			(layer "B.SilkS")
		)
		(fp_line
			(start 0.67945 -0.305054)
			(end 0.12065 -0.305054)
			(stroke
				(width 0.1)
				(type default)
			)
			(layer "B.Fab")
		)
		(fp_line
			(start 0.12065 -0.305054)
			(end 0.12065 -0.2794)
			(stroke
				(width 0.1)
				(type default)
			)
			(layer "B.Fab")
		)
		(fp_line
			(start -0.12065 -0.3048)
			(end -0.67945 -0.3048)
			(stroke
				(width 0.1)
				(type default)
			)
			(layer "B.Fab")
		)
		(fp_line
			(start -0.67945 -0.3048)
			(end -0.67945 0.3048)
			(stroke
				(width 0.1)
				(type default)
			)
			(layer "B.Fab")
		)
		(fp_line
			(start 0.12065 -0.2794)
			(end -0.12065 -0.2794)
			(stroke
				(width 0.1)
				(type default)
			)
			(layer "B.Fab")
		)
		(fp_line
			(start -0.12065 -0.2794)
			(end -0.12065 -0.3048)
			(stroke
				(width 0.1)
				(type default)
			)
			(layer "B.Fab")
		)
		(fp_line
			(start 0.12065 0.2794)
			(end 0.12065 0.3048)
			(stroke
				(width 0.1)
				(type default)
			)
			(layer "B.Fab")
		)
		(fp_line
			(start -0.120396 0.2794)
			(end 0.12065 0.2794)
			(stroke
				(width 0.1)
				(type default)
			)
			(layer "B.Fab")
		)
		(fp_line
			(start 0.67945 0.3048)
			(end 0.67945 -0.305054)
			(stroke
				(width 0.1)
				(type default)
			)
			(layer "B.Fab")
		)
		(fp_line
			(start 0.12065 0.3048)
			(end 0.67945 0.3048)
			(stroke
				(width 0.1)
				(type default)
			)
			(layer "B.Fab")
		)
		(fp_line
			(start -0.120396 0.3048)
			(end -0.120396 0.2794)
			(stroke
				(width 0.1)
				(type default)
			)
			(layer "B.Fab")
		)
		(fp_line
			(start -0.67945 0.3048)
			(end -0.120396 0.3048)
			(stroke
				(width 0.1)
				(type default)
			)
			(layer "B.Fab")
		)
		(pad "1" smd circle
			(at 0.40005 0 270)
			(size 0 0)
			(layers "B.Cu" "B.Mask" "B.Paste")
			(net "INA230_2_A0")
		)
		(pad "2" smd circle
			(at -0.40005 0 270)
			(size 0 0)
			(layers "B.Cu" "B.Mask" "B.Paste")
			(net "SMB_INA230_2_3V3AUX_SDA_R1")
		)
	)
)
